(kicad_pcb
	(version 20241229)
	(generator "pcbnew")
	(generator_version "9.0")
	(general
		(thickness 1.6296)
		(legacy_teardrops no)
	)
	(paper "A3")
	(title_block
		(title "Thunderbolt to 10GbE adapter")
		(date "2026-04-21")
		(rev "1.1.0")
		(company "Antmicro Ltd")
		(comment 1 "www.antmicro.com")
		(comment 9 "footprints 276-279 of 703")
	)
	(layers
		(0 "F.Cu" signal)
		(4 "In1.Cu" signal)
		(6 "In2.Cu" signal)
		(8 "In3.Cu" signal)
		(10 "In4.Cu" signal)
		(12 "In5.Cu" signal)
		(14 "In6.Cu" signal)
		(2 "B.Cu" signal)
		(9 "F.Adhes" user "F.Adhesive")
		(11 "B.Adhes" user "B.Adhesive")
		(13 "F.Paste" user)
		(15 "B.Paste" user)
		(5 "F.SilkS" user "F.Silkscreen")
		(7 "B.SilkS" user "B.Silkscreen")
		(1 "F.Mask" user)
		(3 "B.Mask" user)
		(17 "Dwgs.User" user "User.Drawings")
		(19 "Cmts.User" user "User.Comments")
		(21 "Eco1.User" user "User.Eco1")
		(23 "Eco2.User" user "User.Eco2")
		(25 "Edge.Cuts" user)
		(27 "Margin" user)
		(31 "F.CrtYd" user "F.Courtyard")
		(29 "B.CrtYd" user "B.Courtyard")
		(35 "F.Fab" user)
		(33 "B.Fab" user)
	)
	(footprint "antmicro-footprints:TSSOP-8_3x3mm_P0.65mm"
		(layer "F.Cu")
		(at 165.5 71.674999 -90)
		(property "Reference" "U17"
			(at -1.274999 1.9 270)
			(layer "F.SilkS")
			(effects
				(font
					(size 0.7 0.7)
					(thickness 0.15)
				)
				(justify left bottom)
			)
		)
		(property "Value" "NTS0102_TSSOP"
			(at 0 2.8 270)
			(layer "F.Fab")
			(effects
				(font
					(size 0.7 0.7)
					(thickness 0.15)
				)
				(justify left bottom)
			)
		)
		(property "Datasheet" "https://www.mouser.com/datasheet/2/302/NTS0102-1127324.pdf"
			(at 0 0 270)
			(layer "F.Fab")
			(hide yes)
			(effects
				(font
					(size 1.27 1.27)
					(thickness 0.15)
				)
			)
		)
		(property "Description" "Transceiver, 1.65 V to 3.6 V, TSSOP-8"
			(at 0 0 270)
			(layer "F.Fab")
			(hide yes)
			(effects
				(font
					(size 1.27 1.27)
					(thickness 0.15)
				)
			)
		)
		(property "MPN" "NTS0102DP"
			(at 0 0 270)
			(unlocked yes)
			(layer "F.Fab")
			(hide yes)
			(effects
				(font
					(size 1 1)
					(thickness 0.15)
				)
			)
		)
		(property "Manufacturer" "NXP"
			(at 0 0 270)
			(unlocked yes)
			(layer "F.Fab")
			(hide yes)
			(effects
				(font
					(size 1 1)
					(thickness 0.15)
				)
			)
		)
		(property "Author" "Antmicro"
			(at 0 0 270)
			(unlocked yes)
			(layer "F.Fab")
			(hide yes)
			(effects
				(font
					(size 1 1)
					(thickness 0.15)
				)
			)
		)
		(property "License" "Apache-2.0"
			(at 0 0 270)
			(unlocked yes)
			(layer "F.Fab")
			(hide yes)
			(effects
				(font
					(size 1 1)
					(thickness 0.15)
				)
			)
		)
		(sheetname "/X710-AT2 Misc/")
		(sheetfile "x710-at2-mics.kicad_sch")
		(attr smd)
		(fp_line
			(start -1.55 1.561)
			(end 1.552 1.561)
			(stroke
				(width 0.15)
				(type solid)
			)
			(layer "F.SilkS")
		)
		(fp_line
			(start -1.525 -1.537)
			(end 1.552 -1.539)
			(stroke
				(width 0.15)
				(type solid)
			)
			(layer "F.SilkS")
		)
		(fp_circle
			(center -1.87 -1.4)
			(end -1.82 -1.4)
			(stroke
				(width 0.15)
				(type solid)
			)
			(fill yes)
			(layer "F.SilkS")
		)
		(fp_rect
			(start -3.15 -1.789)
			(end 3.15 1.811)
			(stroke
				(width 0.05)
				(type solid)
			)
			(fill no)
			(layer "F.CrtYd")
		)
		(fp_line
			(start -1.55 1.561)
			(end 1.552 1.561)
			(stroke
				(width 0.15)
				(type solid)
			)
			(layer "F.Fab")
		)
		(fp_line
			(start -1.55 -0.937)
			(end -1.55 1.561)
			(stroke
				(width 0.15)
				(type solid)
			)
			(layer "F.Fab")
		)
		(fp_line
			(start -1.55 -0.937)
			(end -0.949 -1.539)
			(stroke
				(width 0.15)
				(type solid)
			)
			(layer "F.Fab")
		)
		(fp_line
			(start -0.949 -1.539)
			(end 1.552 -1.539)
			(stroke
				(width 0.15)
				(type solid)
			)
			(layer "F.Fab")
		)
		(fp_line
			(start 1.552 -1.539)
			(end 1.552 1.561)
			(stroke
				(width 0.15)
				(type solid)
			)
			(layer "F.Fab")
		)
		(fp_text user "Author: Antmicro"
			(at -1.789 7.78 270)
			(layer "F.Fab")
			(effects
				(font
					(size 0.7 0.7)
					(thickness 0.15)
				)
				(justify left bottom)
			)
		)
		(fp_text user "${REFERENCE}"
			(at -1.789 6.58 270)
			(layer "F.Fab")
			(effects
				(font
					(size 0.7 0.7)
					(thickness 0.15)
				)
				(justify left bottom)
			)
		)
		(fp_text user "License: Apache-2.0"
			(at -1.789 8.98 270)
			(layer "F.Fab")
			(effects
				(font
					(size 0.7 0.7)
					(thickness 0.15)
				)
				(justify left bottom)
			)
		)
		(pad "1" smd roundrect
			(at -2.148 -0.962 270)
			(size 1.47 0.4)
			(layers "F.Cu" "F.Mask" "F.Paste")
			(roundrect_rratio 0.25)
			(net 438 "Net-(U17-B_{2})")
			(pinfunction "B_{2}")
			(pintype "bidirectional")
		)
		(pad "2" smd roundrect
			(at -2.148 -0.313 270)
			(size 1.47 0.4)
			(layers "F.Cu" "F.Mask" "F.Paste")
			(roundrect_rratio 0.25)
			(net 23 "GND")
			(pinfunction "GND")
			(pintype "power_in")
		)
		(pad "3" smd roundrect
			(at -2.148 0.338 270)
			(size 1.47 0.4)
			(layers "F.Cu" "F.Mask" "F.Paste")
			(roundrect_rratio 0.25)
			(net 18 "+1V88")
			(pinfunction "VCC_{A}")
			(pintype "power_in")
		)
		(pad "4" smd roundrect
			(at -2.148 0.987 270)
			(size 1.47 0.4)
			(layers "F.Cu" "F.Mask" "F.Paste")
			(roundrect_rratio 0.25)
			(net 439 "Net-(U17-A_{2})")
			(pinfunction "A_{2}")
			(pintype "bidirectional")
		)
		(pad "5" smd roundrect
			(at 2.151 0.987 270)
			(size 1.47 0.4)
			(layers "F.Cu" "F.Mask" "F.Paste")
			(roundrect_rratio 0.25)
			(net 150 "/X710-AT2 Misc/~{PHY_RESET}")
			(pinfunction "A_{1}")
			(pintype "bidirectional")
		)
		(pad "6" smd roundrect
			(at 2.151 0.338 270)
			(size 1.47 0.4)
			(layers "F.Cu" "F.Mask" "F.Paste")
			(roundrect_rratio 0.25)
			(net 18 "+1V88")
			(pinfunction "OE")
			(pintype "input")
		)
		(pad "7" smd roundrect
			(at 2.151 -0.313 270)
			(size 1.47 0.4)
			(layers "F.Cu" "F.Mask" "F.Paste")
			(roundrect_rratio 0.25)
			(net 7 "+3V3")
			(pinfunction "VCC_{B}")
			(pintype "power_in")
		)
		(pad "8" smd roundrect
			(at 2.151 -0.962 270)
			(size 1.47 0.4)
			(layers "F.Cu" "F.Mask" "F.Paste")
			(roundrect_rratio 0.25)
			(net 146 "/X710-AT2 10GbE/~{PHY_RESET_3V3}")
			(pinfunction "B_{1}")
			(pintype "bidirectional")
		)
	)
	(footprint "antmicro-footprints:C_0402_1005Metric"
		(layer "F.Cu")
		(at 136.149999 111.149999 180)
		(descr "Capacitor SMD 0402")
		(tags "capacitor SMD 0402")
		(property "Reference" "C130"
			(at -16.549997 -17.25 180)
			(layer "F.SilkS")
			(effects
				(font
					(size 0.7 0.7)
					(thickness 0.15)
				)
			)
		)
		(property "Value" "C_33p_0402"
			(at -1.022927 2.155213 180)
			(layer "F.Fab")
			(effects
				(font
					(size 0.7 0.7)
					(thickness 0.15)
				)
				(justify left bottom)
			)
		)
		(property "Datasheet" "https://spicat.kyocera-avx.com/product/mlcc/chartview/04025A330FAT2A/"
			(at 0 0 180)
			(layer "F.Fab")
			(hide yes)
			(effects
				(font
					(size 1.27 1.27)
					(thickness 0.15)
				)
			)
		)
		(property "Description" "SMD Multilayer Ceramic Capacitor, 33 pF, 50 V, 0402 [1005 Metric], ± 5%, C0G / NP0, MC"
			(at 0 0 180)
			(layer "F.Fab")
			(hide yes)
			(effects
				(font
					(size 1.27 1.27)
					(thickness 0.15)
				)
			)
		)
		(property "MPN" "04025A330FAT2A"
			(at 0 0 180)
			(unlocked yes)
			(layer "F.Fab")
			(hide yes)
			(effects
				(font
					(size 1 1)
					(thickness 0.15)
				)
			)
		)
		(property "Manufacturer" "KYOCERA AVX"
			(at 0 0 180)
			(unlocked yes)
			(layer "F.Fab")
			(hide yes)
			(effects
				(font
					(size 1 1)
					(thickness 0.15)
				)
			)
		)
		(property "License" "Apache-2.0"
			(at 0 0 180)
			(unlocked yes)
			(layer "F.Fab")
			(hide yes)
			(effects
				(font
					(size 1 1)
					(thickness 0.15)
				)
			)
		)
		(property "Author" "Antmicro"
			(at 0 0 180)
			(unlocked yes)
			(layer "F.Fab")
			(hide yes)
			(effects
				(font
					(size 1 1)
					(thickness 0.15)
				)
			)
		)
		(property "Val" "33p"
			(at 0 0 180)
			(unlocked yes)
			(layer "F.Fab")
			(hide yes)
			(effects
				(font
					(size 1 1)
					(thickness 0.15)
				)
			)
		)
		(property "Voltage" ""
			(at 0 0 180)
			(unlocked yes)
			(layer "F.Fab")
			(hide yes)
			(effects
				(font
					(size 1 1)
					(thickness 0.15)
				)
			)
		)
		(property "Dielectric" ""
			(at 0 0 180)
			(unlocked yes)
			(layer "F.Fab")
			(hide yes)
			(effects
				(font
					(size 1 1)
					(thickness 0.15)
				)
			)
		)
		(sheetname "/X710 DCDC converters/")
		(sheetfile "DCDC_converters_X710.kicad_sch")
		(attr smd dnp)
		(fp_rect
			(start -0.925 -0.47)
			(end 0.925 0.47)
			(stroke
				(width 0.05)
				(type default)
			)
			(fill no)
			(layer "F.CrtYd")
		)
		(fp_line
			(start 0.504 0.248)
			(end -0.494 0.248)
			(stroke
				(width 0.15)
				(type solid)
			)
			(layer "F.Fab")
		)
		(fp_line
			(start 0.504 -0.25)
			(end 0.504 0.248)
			(stroke
				(width 0.15)
				(type solid)
			)
			(layer "F.Fab")
		)
		(fp_line
			(start -0.494 0.248)
			(end -0.494 -0.25)
			(stroke
				(width 0.15)
				(type solid)
			)
			(layer "F.Fab")
		)
		(fp_line
			(start -0.494 -0.25)
			(end 0.504 -0.25)
			(stroke
				(width 0.15)
				(type solid)
			)
			(layer "F.Fab")
		)
		(fp_text user "${REFERENCE}"
			(at -0.939 4.599 180)
			(layer "F.Fab")
			(effects
				(font
					(size 0.7 0.7)
					(thickness 0.15)
				)
				(justify left bottom)
			)
		)
		(fp_text user "License: Apache-2.0"
			(at -0.939 5.799 180)
			(layer "F.Fab")
			(effects
				(font
					(size 0.7 0.7)
					(thickness 0.15)
				)
				(justify left bottom)
			)
		)
		(fp_text user "Author: Antmicro"
			(at -0.939 3.399 180)
			(layer "F.Fab")
			(effects
				(font
					(size 0.7 0.7)
					(thickness 0.15)
				)
				(justify left bottom)
			)
		)
		(pad "1" smd roundrect
			(at -0.48 0 180)
			(size 0.59 0.64)
			(layers "F.Cu" "F.Mask" "F.Paste")
			(roundrect_rratio 0.25)
			(net 336 "/X710 DCDC converters/VCCD_FB")
			(pintype "passive")
		)
		(pad "2" smd roundrect
			(at 0.48 0 180)
			(size 0.59 0.64)
			(layers "F.Cu" "F.Mask" "F.Paste")
			(roundrect_rratio 0.25)
			(net 335 "/X710 DCDC converters/+VCCD_OUT")
			(pintype "passive")
		)
	)
	(footprint "antmicro-footprints:C_0603_1608Metric"
		(layer "F.Cu")
		(at 153.004998 66.024998 90)
		(descr "Capacitor SMD 0603")
		(tags "capacitor 0603")
		(property "Reference" "C216"
			(at 12.424999 20.045 90)
			(layer "F.SilkS")
			(effects
				(font
					(size 0.7 0.7)
					(thickness 0.15)
				)
			)
		)
		(property "Value" "C_10u_10V_X7R_0603"
			(at -1.42757 1.770288 90)
			(layer "F.Fab")
			(effects
				(font
					(size 0.7 0.7)
					(thickness 0.15)
				)
				(justify left bottom)
			)
		)
		(property "Datasheet" "https://www.murata.com/products/productdetail?partno=GRM188Z71A106KA73%23"
			(at 0 0 90)
			(layer "F.Fab")
			(hide yes)
			(effects
				(font
					(size 1.27 1.27)
					(thickness 0.15)
				)
			)
		)
		(property "Description" "SMD Multilayer Ceramic Capacitor,  10µF, 10V, 0603, ±10%, X7R"
			(at 0 0 90)
			(layer "F.Fab")
			(hide yes)
			(effects
				(font
					(size 1.27 1.27)
					(thickness 0.15)
				)
			)
		)
		(property "MPN" "GRM188Z71A106KA73D"
			(at 0 0 90)
			(unlocked yes)
			(layer "F.Fab")
			(hide yes)
			(effects
				(font
					(size 1 1)
					(thickness 0.15)
				)
			)
		)
		(property "Val" "10u"
			(at 0 0 90)
			(unlocked yes)
			(layer "F.Fab")
			(hide yes)
			(effects
				(font
					(size 1 1)
					(thickness 0.15)
				)
			)
		)
		(property "Voltage" "10V"
			(at 0 0 90)
			(unlocked yes)
			(layer "F.Fab")
			(hide yes)
			(effects
				(font
					(size 1 1)
					(thickness 0.15)
				)
			)
		)
		(property "Dielectric" "X7R"
			(at 0 0 90)
			(unlocked yes)
			(layer "F.Fab")
			(hide yes)
			(effects
				(font
					(size 1 1)
					(thickness 0.15)
				)
			)
		)
		(property "Manufacturer" "Murata"
			(at 0 0 90)
			(unlocked yes)
			(layer "F.Fab")
			(hide yes)
			(effects
				(font
					(size 1 1)
					(thickness 0.15)
				)
			)
		)
		(property "License" "Apache-2.0"
			(at 0 0 90)
			(unlocked yes)
			(layer "F.Fab")
			(hide yes)
			(effects
				(font
					(size 1 1)
					(thickness 0.15)
				)
			)
		)
		(property "Author" "Antmicro"
			(at 0 0 90)
			(unlocked yes)
			(layer "F.Fab")
			(hide yes)
			(effects
				(font
					(size 1 1)
					(thickness 0.15)
				)
			)
		)
		(sheetname "/X710-AT2 power/")
		(sheetfile "x710-at2-power.kicad_sch")
		(attr smd)
		(fp_line
			(start -0.15 -0.4)
			(end 0.15 -0.4)
			(stroke
				(width 0.15)
				(type solid)
			)
			(layer "F.SilkS")
		)
		(fp_line
			(start -0.15 0.4)
			(end 0.15 0.4)
			(stroke
				(width 0.15)
				(type solid)
			)
			(layer "F.SilkS")
		)
		(fp_rect
			(start -1.25 -0.65)
			(end 1.25 0.65)
			(stroke
				(width 0.05)
				(type solid)
			)
			(fill no)
			(layer "F.CrtYd")
		)
		(fp_rect
			(start -0.8 -0.4)
			(end 0.8 0.4)
			(stroke
				(width 0.15)
				(type solid)
			)
			(fill no)
			(layer "F.Fab")
		)
		(fp_text user "Author: Antmicro"
			(at -1.682 4.894 90)
			(layer "F.Fab")
			(effects
				(font
					(size 0.7 0.7)
					(thickness 0.15)
				)
				(justify left bottom)
			)
		)
		(fp_text user "${REFERENCE}"
			(at -1.682 3.895 90)
			(layer "F.Fab")
			(effects
				(font
					(size 0.7 0.7)
					(thickness 0.15)
				)
				(justify left bottom)
			)
		)
		(fp_text user "License: Apache-2.0"
			(at -1.682 5.895 90)
			(layer "F.Fab")
			(effects
				(font
					(size 0.7 0.7)
					(thickness 0.15)
				)
				(justify left bottom)
			)
		)
		(pad "1" smd roundrect
			(at -0.7 0 90)
			(size 0.8 1)
			(layers "F.Cu" "F.Mask" "F.Paste")
			(roundrect_rratio 0.2)
			(net 23 "GND")
			(pintype "passive")
		)
		(pad "2" smd roundrect
			(at 0.7 0 90)
			(size 0.8 1)
			(layers "F.Cu" "F.Mask" "F.Paste")
			(roundrect_rratio 0.2)
			(net 1 "VCCA")
			(pintype "passive")
		)
	)
	(footprint "antmicro-footprints:C_0603_1608Metric_EIA"
		(layer "F.Cu")
		(at 159.55 105.600001 90)
		(descr "Capacitor SMD 0603, IPC-7351 Density Level A")
		(tags "Capacitor 0603")
		(property "Reference" "C142"
			(at -17.849995 13.250002 90)
			(layer "F.SilkS")
			(effects
				(font
					(size 0.7 0.7)
					(thickness 0.15)
				)
			)
		)
		(property "Value" "C_22u_16V_0603"
			(at -1.42757 1.770288 90)
			(layer "F.Fab")
			(effects
				(font
					(size 0.7 0.7)
					(thickness 0.15)
				)
				(justify left bottom)
			)
		)
		(property "Datasheet" "https://product.samsungsem.com/mlcc/CL10A226MO7JZN.do"
			(at 0 0 90)
			(layer "F.Fab")
			(hide yes)
			(effects
				(font
					(size 1.27 1.27)
					(thickness 0.15)
				)
			)
		)
		(property "Description" "SMD Multilayer Ceramic Capacitor"
			(at 0 0 90)
			(layer "F.Fab")
			(hide yes)
			(effects
				(font
					(size 1.27 1.27)
					(thickness 0.15)
				)
			)
		)
		(property "MPN" "CL10A226MO7JZNC"
			(at 0 0 90)
			(unlocked yes)
			(layer "F.Fab")
			(hide yes)
			(effects
				(font
					(size 1 1)
					(thickness 0.15)
				)
			)
		)
		(property "Manufacturer" "Samsung Electro-Mechanics"
			(at 0 0 90)
			(unlocked yes)
			(layer "F.Fab")
			(hide yes)
			(effects
				(font
					(size 1 1)
					(thickness 0.15)
				)
			)
		)
		(property "License" "Apache-2.0"
			(at 0 0 90)
			(unlocked yes)
			(layer "F.Fab")
			(hide yes)
			(effects
				(font
					(size 1 1)
					(thickness 0.15)
				)
			)
		)
		(property "Author" "Antmicro"
			(at 0 0 90)
			(unlocked yes)
			(layer "F.Fab")
			(hide yes)
			(effects
				(font
					(size 1 1)
					(thickness 0.15)
				)
			)
		)
		(property "Val" "22u"
			(at 0 0 90)
			(unlocked yes)
			(layer "F.Fab")
			(hide yes)
			(effects
				(font
					(size 1 1)
					(thickness 0.15)
				)
			)
		)
		(property "Voltage" "16V"
			(at 0 0 90)
			(unlocked yes)
			(layer "F.Fab")
			(hide yes)
			(effects
				(font
					(size 1 1)
					(thickness 0.15)
				)
			)
		)
		(property "Dielectric" ""
			(at 0 0 90)
			(unlocked yes)
			(layer "F.Fab")
			(hide yes)
			(effects
				(font
					(size 1 1)
					(thickness 0.15)
				)
			)
		)
		(sheetname "/X710 DCDC converters/")
		(sheetfile "DCDC_converters_X710.kicad_sch")
		(attr smd)
		(fp_line
			(start -0.15 -0.55)
			(end 0.15 -0.55)
			(stroke
				(width 0.15)
				(type solid)
			)
			(layer "F.SilkS")
		)
		(fp_line
			(start -0.15 0.55)
			(end 0.15 0.55)
			(stroke
				(width 0.15)
				(type solid)
			)
			(layer "F.SilkS")
		)
		(fp_rect
			(start -1.25 -0.65)
			(end 1.25 0.65)
			(stroke
				(width 0.05)
				(type solid)
			)
			(fill no)
			(layer "F.CrtYd")
		)
		(fp_rect
			(start -0.8 -0.45)
			(end 0.8 0.45)
			(stroke
				(width 0.15)
				(type solid)
			)
			(fill no)
			(layer "F.Fab")
		)
		(fp_text user "Author: Antmicro"
			(at -1.682 4.894 90)
			(layer "F.Fab")
			(effects
				(font
					(size 0.7 0.7)
					(thickness 0.15)
				)
				(justify left bottom)
			)
		)
		(fp_text user "License: Apache-2.0"
			(at -1.682 5.895 90)
			(layer "F.Fab")
			(effects
				(font
					(size 0.7 0.7)
					(thickness 0.15)
				)
				(justify left bottom)
			)
		)
		(fp_text user "${REFERENCE}"
			(at -1.682 3.895 90)
			(layer "F.Fab")
			(effects
				(font
					(size 0.7 0.7)
					(thickness 0.15)
				)
				(justify left bottom)
			)
		)
		(pad "1" smd roundrect
			(at -0.7 0 90)
			(size 0.8 1.1)
			(layers "F.Cu" "F.Mask" "F.Paste")
			(roundrect_rratio 0.2)
			(net 23 "GND")
			(pintype "passive")
		)
		(pad "2" smd roundrect
			(at 0.7 0 90)
			(size 0.8 1.1)
			(layers "F.Cu" "F.Mask" "F.Paste")
			(roundrect_rratio 0.2)
			(net 339 "/X710 DCDC converters/+1V0_OUT")
			(pintype "passive")
		)
	)
)
